# S9S_MB_2U (Grand Teton) — schematic netlist excerpt (pin names and nets, part order shuffled) for the footprints in the layout excerpt that follows; sources: Cadence DE-HDL packaged netlist, KiCad conversion of 03242023_DA0F0TMBIJ0_F0T_Motherboard_J_brd_V01_OCP.brd

J20  SCONN288_ADR50017P087CC  SCONN288_ADR50017-P087CC IO  pkg DDR288S_1-1VXB  page 101
  VIN_BULK0  = P12V_S3_AUX_CPU1_NVDIMM
  RFU0  = TP_CHB_CPU1_DIMM2_FRU_0
  VIN_MGMT  = P3V3_AUX
  HSCL  = I3C_SPD_DDRABCD_CPU1_LVC1_SCL_3
  HSDA  = I3C_SPD_DDRABCD_CPU1_LVC1_SDA
  VSS0  = GND
  DQ0_A  = M_B_CPU1_SA_DQ<0>
  VSS1  = GND
  DQ1_A  = M_B_CPU1_SA_DQ<1>
  VSS2  = GND
  DQS0_A_T  = M_B_CPU1_SA_DQS_DP<0>
  DQS0_A_C  = M_B_CPU1_SA_DQS_DN<0>
  VSS3  = GND
  DQ4_A  = M_B_CPU1_SA_DQ<4>
  VSS4  = GND
  DQ5_A  = M_B_CPU1_SA_DQ<5>
  VSS5  = GND
  DQ8_A  = M_B_CPU1_SA_DQ<8>
  VSS6  = GND
  DQ9_A  = M_B_CPU1_SA_DQ<9>
  VSS7  = GND
  DQS1_A_T  = M_B_CPU1_SA_DQS_DP<1>
  DQS1_A_C  = M_B_CPU1_SA_DQS_DN<1>
  VSS8  = GND
  DQ12_A  = M_B_CPU1_SA_DQ<12>
  VSS9  = GND
  DQ13_A  = M_B_CPU1_SA_DQ<13>
  VSS10  = GND
  DQ16_A  = M_B_CPU1_SA_DQ<16>
  VSS11  = GND
  DQ17_A  = M_B_CPU1_SA_DQ<17>
  VSS12  = GND
  DQS2_A_T  = M_B_CPU1_SA_DQS_DP<2>
  DQS2_A_C  = M_B_CPU1_SA_DQS_DN<2>
  VSS13  = GND
  DQ20_A  = M_B_CPU1_SA_DQ<20>
  VSS14  = GND
  DQ21_A  = M_B_CPU1_SA_DQ<21>
  VSS15  = GND
  DQ24_A  = M_B_CPU1_SA_DQ<24>
  VSS16  = GND
  DQ25_A  = M_B_CPU1_SA_DQ<25>
  VSS17  = GND
  DQS3_A_T  = M_B_CPU1_SA_DQS_DP<3>
  DQS3_A_C  = M_B_CPU1_SA_DQS_DN<3>
  VSS18  = GND
  DQ28_A  = M_B_CPU1_SA_DQ<28>
  VSS19  = GND
  DQ29_A  = M_B_CPU1_SA_DQ<29>
  VSS20  = GND
  CB0_A  = M_B_CPU1_SA_CB<0>
  VSS21  = GND
  CB1_A  = M_B_CPU1_SA_CB<1>
  VSS22  = GND
  DQS4_A_T  = M_B_CPU1_SA_DQS_DP<4>
  DQS4_A_C  = M_B_CPU1_SA_DQS_DN<4>
  VSS23  = GND
  CB4_A  = M_B_CPU1_SA_CB<4>
  VSS24  = GND
  CB5_A  = M_B_CPU1_SA_CB<5>
  VSS25  = GND
  ALERT_N  = M_B_CPU1_ALERT_N
  VSS26  = GND
  CS0_A_N  = M_B_CPU1_SA_CS_N<2>
  VSS27  = GND
  CA0_A  = M_B_CPU1_SA_CA<0>
  VSS28  = GND
  CA2_A  = M_B_CPU1_SA_CA<2>
  VSS29  = GND
  CA4_A  = M_B_CPU1_SA_CA<4>
  VSS30  = GND
  CA6_A  = M_B_CPU1_SA_CA<6>
  VSS31  = GND
  PAR_A  = M_B_CPU1_SA_PAR
  VSS32  = GND
  CA0_B  = M_B_CPU1_SB_CA<0>
  VSS33  = GND
  CA2_B  = M_B_CPU1_SB_CA<2>
  VSS34  = GND
  CA4_B  = M_B_CPU1_SB_CA<4>
  VSS35  = GND
  CA6_B  = M_B_CPU1_SB_CA<6>
  VSS36  = GND
  CS0_B_N  = M_B_CPU1_SB_CS_N<2>
  VSS37  = GND
  \lbd||rsp_a_n\  = M_B_CPU1_SA_RSP<1>
  \lbs||rsp_b_n\  = M_B_CPU1_SB_RSP<1>
  VSS38  = GND
  CB4_B  = M_B_CPU1_SB_CB<4>
  VSS39  = GND
  CB5_B  = M_B_CPU1_SB_CB<5>
  VSS40  = GND
  \dqs9_b_t||tdqs9_b_t||dbi4_b_n\  = M_B_CPU1_SB_DQS_DP<9>
  \dqs9_b_c||tdqs9_b_c\  = M_B_CPU1_SB_DQS_DN<9>
  VSS41  = GND
  CB0_B  = M_B_CPU1_SB_CB<0>
  VSS42  = GND
  CB1_B  = M_B_CPU1_SB_CB<1>
  VSS43  = GND
  DQ0_B  = M_B_CPU1_SB_DQ<0>
  VSS44  = GND
  DQ1_B  = M_B_CPU1_SB_DQ<1>
  VSS45  = GND
  DQS0_B_T  = M_B_CPU1_SB_DQS_DP<0>
  DQS0_B_C  = M_B_CPU1_SB_DQS_DN<0>
  VSS46  = GND
  DQ4_B  = M_B_CPU1_SB_DQ<4>
  VSS47  = GND
  DQ5_B  = M_B_CPU1_SB_DQ<5>
  VSS48  = GND
  DQ8_B  = M_B_CPU1_SB_DQ<8>
  VSS49  = GND
  DQ9_B  = M_B_CPU1_SB_DQ<9>
  VSS50  = GND
  DQS1_B_T  = M_B_CPU1_SB_DQS_DP<1>
  DQS1_B_C  = M_B_CPU1_SB_DQS_DN<1>
  VSS51  = GND
  DQ12_B  = M_B_CPU1_SB_DQ<12>
  VSS52  = GND
  DQ13_B  = M_B_CPU1_SB_DQ<13>
  VSS53  = GND
  DQ16_B  = M_B_CPU1_SB_DQ<16>
  VSS54  = GND
  DQ17_B  = M_B_CPU1_SB_DQ<17>
  VSS55  = GND
  DQS2_B_T  = M_B_CPU1_SB_DQS_DP<2>
  DQS2_B_C  = M_B_CPU1_SB_DQS_DN<2>
  VSS56  = GND
  DQ20_B  = M_B_CPU1_SB_DQ<20>
  VSS57  = GND
  DQ21_B  = M_B_CPU1_SB_DQ<21>
  VSS58  = GND
  DQ24_B  = M_B_CPU1_SB_DQ<24>
  VSS59  = GND
  DQ25_B  = M_B_CPU1_SB_DQ<25>
  VSS60  = GND
  DQS3_B_T  = M_B_CPU1_SB_DQS_DP<3>
  DQS3_B_C  = M_B_CPU1_SB_DQS_DN<3>
  VSS61  = GND
  DQ28_B  = M_B_CPU1_SB_DQ<28>
  VSS62  = GND
  DQ29_B  = M_B_CPU1_SB_DQ<29>
  VSS63  = GND
  RFU1  = TP_CHB_CPU1_DIMM2_FRU_1
  VIN_BULK1  = P12V_S3_AUX_CPU1_NVDIMM
  VIN_BULK2  = P12V_S3_AUX_CPU1_NVDIMM
  \pwr_good||fail_n\  = PWRGD_CHB_CPU1_DIMM2
  HSA  = PD_CHB_CPU1_DIMM2_SAA
  RFU2  = TP_CHB_CPU1_DIMM2_FRU_2
  RFU3  = TP_CHB_CPU1_DIMM2_FRU_3
  VSS64  = GND
  DQ2_A  = M_B_CPU1_SA_DQ<2>
  VSS65  = GND
  DQ3_A  = M_B_CPU1_SA_DQ<3>
  VSS66  = GND
  \dqs5_a_c||tdqs5_a_c||dqs5_a_t||tdqs5_a_t\  = M_B_CPU1_SA_DQS_DN<5>
  \dqs5_a_t||tdqs5_a_t\  = M_B_CPU1_SA_DQS_DP<5>
  VSS67  = GND
  DQ6_A  = M_B_CPU1_SA_DQ<6>
  VSS68  = GND
  DQ7_A  = M_B_CPU1_SA_DQ<7>
  VSS69  = GND
  DQ10_A  = M_B_CPU1_SA_DQ<10>
  VSS70  = GND
  DQ11_A  = M_B_CPU1_SA_DQ<11>
  VSS71  = GND
  \dqs6_a_c||tdqs6_a_c||dqs6_a_t||tdqs6_a_t\  = M_B_CPU1_SA_DQS_DN<6>
  \dqs6_a_t||tdqs6_a_t\  = M_B_CPU1_SA_DQS_DP<6>
  VSS72  = GND
  DQ14_A  = M_B_CPU1_SA_DQ<14>
  VSS73  = GND
  DQ15_A  = M_B_CPU1_SA_DQ<15>
  VSS74  = GND
  DQ18_A  = M_B_CPU1_SA_DQ<18>
  VSS75  = GND
  DQ19_A  = M_B_CPU1_SA_DQ<19>
  VSS76  = GND
  \dqs7_a_c||tdqs7_a_c\  = M_B_CPU1_SA_DQS_DN<7>
  \dqs7_a_t||tdqs7_a_t\  = M_B_CPU1_SA_DQS_DP<7>
  VSS77  = GND
  DQ22_A  = M_B_CPU1_SA_DQ<22>
  VSS78  = GND
  DQ23_A  = M_B_CPU1_SA_DQ<23>
  VSS79  = GND
  DQ26_A  = M_B_CPU1_SA_DQ<26>
  VSS80  = GND
  DQ27_A  = M_B_CPU1_SA_DQ<27>
  VSS81  = GND
  \dqs8_a_c||tdqs8_a_c\  = M_B_CPU1_SA_DQS_DN<8>
  \dqs8_a_t||tdqs8_a_t\  = M_B_CPU1_SA_DQS_DP<8>
  VSS82  = GND
  DQ30_A  = M_B_CPU1_SA_DQ<30>
  VSS83  = GND
  DQ31_A  = M_B_CPU1_SA_DQ<31>
  VSS84  = GND
  CB2_A  = M_B_CPU1_SA_CB<2>
  VSS85  = GND
  CB3_A  = M_B_CPU1_SA_CB<3>
  VSS86  = GND
  \dqs9_a_c||tdqs9_a_c\  = M_B_CPU1_SA_DQS_DN<9>
  \dqs9_a_t||tdqs9_a_t\  = M_B_CPU1_SA_DQS_DP<9>
  VSS87  = GND
  CB6_A  = M_B_CPU1_SA_CB<6>
  VSS88  = GND
  CB7_A  = M_B_CPU1_SA_CB<7>
  VSS89  = GND
  RESET_N  = RST_M_AB_CPU1_FPGA_N
  VSS90  = GND
  CS1_A_N  = M_B_CPU1_SA_CS_N<3>
  VSS91  = GND
  CA1_A  = M_B_CPU1_SA_CA<1>
  VSS92  = GND
  CA3_A  = M_B_CPU1_SA_CA<3>
  VSS93  = GND
  CA5_A  = M_B_CPU1_SA_CA<5>
  VSS94  = GND
  CK_T  = M_B_CPU1_CLK_DP<1>
  CK_C  = M_B_CPU1_CLK_DN<1>
  VSS95  = GND
  RFU4  = TP_CHB_CPU1_DIMM2_FRU_4
  CA1_B  = M_B_CPU1_SB_CA<1>
  VSS96  = GND
  CA3_B  = M_B_CPU1_SB_CA<3>
  VSS97  = GND
  CA5_B  = M_B_CPU1_SB_CA<5>
  VSS98  = GND
  PAR_B  = M_B_CPU1_SB_PAR
  VSS99  = GND
  CS1_B_N  = M_B_CPU1_SB_CS_N<3>
  VSS100  = GND
  RFU5  = TP_CHB_CPU1_DIMM2_FRU_5
  RFU6  = TP_CHB_CPU1_DIMM2_FRU_6
  VSS101  = GND
  CB6_B  = M_B_CPU1_SB_CB<6>
  VSS102  = GND
  CB7_B  = M_B_CPU1_SB_CB<7>
  VSS103  = GND
  DQS4_B_C  = M_B_CPU1_SB_DQS_DN<4>
  DQS4_B_T  = M_B_CPU1_SB_DQS_DP<4>
  VSS104  = GND
  CB2_B  = M_B_CPU1_SB_CB<2>
  VSS105  = GND
  CB3_B  = M_B_CPU1_SB_CB<3>
  VSS106  = GND
  DQ2_B  = M_B_CPU1_SB_DQ<2>
  VSS107  = GND
  DQ3_B  = M_B_CPU1_SB_DQ<3>
  VSS108  = GND
  \dqs5_b_c||tdqs5_b_c\  = M_B_CPU1_SB_DQS_DN<5>
  \dqs5_b_t||tdqs5_b_t\  = M_B_CPU1_SB_DQS_DP<5>
  VSS109  = GND
  DQ6_B  = M_B_CPU1_SB_DQ<6>
  VSS110  = GND
  DQ7_B  = M_B_CPU1_SB_DQ<7>
  VSS111  = GND
  DQ10_B  = M_B_CPU1_SB_DQ<10>
  VSS112  = GND
  DQ11_B  = M_B_CPU1_SB_DQ<11>
  VSS113  = GND
  \dqs6_b_c||tdqs6_b_c\  = M_B_CPU1_SB_DQS_DN<6>
  \dqs6_b_t||tdqs6_b_t\  = M_B_CPU1_SB_DQS_DP<6>
  VSS114  = GND
  DQ14_B  = M_B_CPU1_SB_DQ<14>
  VSS115  = GND
  DQ15_B  = M_B_CPU1_SB_DQ<15>
  VSS116  = GND
  DQ18_B  = M_B_CPU1_SB_DQ<18>
  VSS117  = GND
  DQ19_B  = M_B_CPU1_SB_DQ<19>
  VSS118  = GND
  \dqs7_b_c||tdqs7_b_c\  = M_B_CPU1_SB_DQS_DN<7>
  \dqs7_b_t||tdqs7_b_t\  = M_B_CPU1_SB_DQS_DP<7>
  VSS119  = GND
  DQ22_B  = M_B_CPU1_SB_DQ<22>
  VSS120  = GND
  DQ23_B  = M_B_CPU1_SB_DQ<23>
  VSS121  = GND
  DQ26_B  = M_B_CPU1_SB_DQ<26>
  VSS122  = GND
  DQ27_B  = M_B_CPU1_SB_DQ<27>
  VSS123  = GND
  \dqs8_b_c||tdqs8_b_c\  = M_B_CPU1_SB_DQS_DN<8>
  \dqs8_b_t||tdqs8_b_t\  = M_B_CPU1_SB_DQS_DP<8>
  VSS124  = GND
  DQ30_B  = M_B_CPU1_SB_DQ<30>
  VSS125  = GND
  DQ31_B  = M_B_CPU1_SB_DQ<31>
  VSS126  = GND
  G1  = GND
  G2  = GND
  G3  = GND

(kicad_pcb
	(version 20260206)
	(generator "pcbnew")
	(generator_version "10.0")
	(general
		(thickness 1.6)
		(legacy_teardrops no)
	)
	(paper "A4")
	(title_block
		(title "03242023_DA0F0TMBIJ0_F0T_Motherboard_J_brd_V01_OCP.brd")
		(comment 1 "Grand Teton / footprint 1508 of 6105 (J20), pads 92-137 of 291")
	)
	(layers
		(0 "F.Cu" signal "TOP")
		(4 "In1.Cu" signal "GND")
		(6 "In2.Cu" signal "IN1")
		(8 "In3.Cu" signal "GND1")
		(10 "In4.Cu" signal "IN2")
		(12 "In5.Cu" signal "GND2")
		(14 "In6.Cu" signal "IN3")
		(16 "In7.Cu" signal "GND3")
		(18 "In8.Cu" signal "VCC")
		(20 "In9.Cu" signal "VCC1")
		(22 "In10.Cu" signal "GND4")
		(24 "In11.Cu" signal "IN4")
		(26 "In12.Cu" signal "GND5")
		(28 "In13.Cu" signal "IN5")
		(30 "In14.Cu" signal "GND6")
		(32 "In15.Cu" signal "IN6")
		(34 "In16.Cu" signal "GND7")
		(2 "B.Cu" signal "BOTTOM")
		(9 "F.Adhes" user "F.Adhesive")
		(11 "B.Adhes" user "B.Adhesive")
		(13 "F.Paste" user "Package Geometry/Pastemask Top")
		(15 "B.Paste" user "Package Geometry/Pastemask Bottom")
		(5 "F.SilkS" user "Ref Des/Silkscreen Top")
		(7 "B.SilkS" user "Ref Des/Silkscreen Bottom")
		(1 "F.Mask" user "Board Geometry/Soldermask Top")
		(3 "B.Mask" user "Board Geometry/Soldermask Bottom")
		(17 "Dwgs.User" user "User.Drawings")
		(19 "Cmts.User" user "User.Comments")
		(21 "Eco1.User" user "User.Eco1")
		(23 "Eco2.User" user "User.Eco2")
		(25 "Edge.Cuts" user "Board Geometry/Outline")
		(27 "Margin" user)
		(31 "F.CrtYd" user "Package Geometry/Place Bound Top")
		(29 "B.CrtYd" user "Package Geometry/Place Bound Bottom")
		(35 "F.Fab" user "Ref Des/Assembly Top")
		(33 "B.Fab" user "Ref Des/Assembly Bottom")
	)
	(footprint ""
		(layer "F.Cu")
		(at 47.90948 -258.091686)
		(property "Reference" "J20"
			(at -2.74066 -81.678272 0)
			(unlocked yes)
			(layer "F.SilkS")
			(effects
				(font
					(size 0.7874 0.5842)
					(thickness 0.1524)
				)
				(justify left)
			)
		)
		(property "Value" ""
			(at 0 0 0)
			(layer "F.Fab")
			(effects
				(font
					(size 1.27 1.27)
				)
			)
		)
		(duplicate_pad_numbers_are_jumpers no)
		(pad "92" smd rect
			(at -2.050034 19.12493 270)
			(size 0.519938 1.4986)
			(layers "F.Cu" "F.Mask" "F.Paste")
			(net "GND")
		)
		(pad "93" smd rect
			(at -2.050034 19.975068 270)
			(size 0.519938 1.4986)
			(layers "F.Cu" "F.Mask" "F.Paste")
			(net "M_B_CPU1_SB_DQS_DP<9>")
		)
		(pad "94" smd rect
			(at -2.050034 20.824952 270)
			(size 0.519938 1.4986)
			(layers "F.Cu" "F.Mask" "F.Paste")
			(net "M_B_CPU1_SB_DQS_DN<9>")
		)
		(pad "95" smd rect
			(at -2.050034 21.67509 270)
			(size 0.519938 1.4986)
			(layers "F.Cu" "F.Mask" "F.Paste")
			(net "GND")
		)
		(pad "96" smd rect
			(at -2.050034 22.524974 270)
			(size 0.519938 1.4986)
			(layers "F.Cu" "F.Mask" "F.Paste")
			(net "M_B_CPU1_SB_CB<0>")
		)
		(pad "97" smd rect
			(at -2.050034 23.375112 270)
			(size 0.519938 1.4986)
			(layers "F.Cu" "F.Mask" "F.Paste")
			(net "GND")
		)
		(pad "98" smd rect
			(at -2.050034 24.224996 270)
			(size 0.519938 1.4986)
			(layers "F.Cu" "F.Mask" "F.Paste")
			(net "M_B_CPU1_SB_CB<1>")
		)
		(pad "99" smd rect
			(at -2.050034 25.07488 270)
			(size 0.519938 1.4986)
			(layers "F.Cu" "F.Mask" "F.Paste")
			(net "GND")
		)
		(pad "100" smd rect
			(at -2.050034 25.925018 270)
			(size 0.519938 1.4986)
			(layers "F.Cu" "F.Mask" "F.Paste")
			(net "M_B_CPU1_SB_DQ<0>")
		)
		(pad "101" smd rect
			(at -2.050034 26.774902 270)
			(size 0.519938 1.4986)
			(layers "F.Cu" "F.Mask" "F.Paste")
			(net "GND")
		)
		(pad "102" smd rect
			(at -2.050034 27.62504 270)
			(size 0.519938 1.4986)
			(layers "F.Cu" "F.Mask" "F.Paste")
			(net "M_B_CPU1_SB_DQ<1>")
		)
		(pad "103" smd rect
			(at -2.050034 28.474924 270)
			(size 0.519938 1.4986)
			(layers "F.Cu" "F.Mask" "F.Paste")
			(net "GND")
		)
		(pad "104" smd rect
			(at -2.050034 29.325062 270)
			(size 0.519938 1.4986)
			(layers "F.Cu" "F.Mask" "F.Paste")
			(net "M_B_CPU1_SB_DQS_DP<0>")
		)
		(pad "105" smd rect
			(at -2.050034 30.174946 270)
			(size 0.519938 1.4986)
			(layers "F.Cu" "F.Mask" "F.Paste")
			(net "M_B_CPU1_SB_DQS_DN<0>")
		)
		(pad "106" smd rect
			(at -2.050034 31.025084 270)
			(size 0.519938 1.4986)
			(layers "F.Cu" "F.Mask" "F.Paste")
			(net "GND")
		)
		(pad "107" smd rect
			(at -2.050034 31.874968 270)
			(size 0.519938 1.4986)
			(layers "F.Cu" "F.Mask" "F.Paste")
			(net "M_B_CPU1_SB_DQ<4>")
		)
		(pad "108" smd rect
			(at -2.050034 32.725106 270)
			(size 0.519938 1.4986)
			(layers "F.Cu" "F.Mask" "F.Paste")
			(net "GND")
		)
		(pad "109" smd rect
			(at -2.050034 33.57499 270)
			(size 0.519938 1.4986)
			(layers "F.Cu" "F.Mask" "F.Paste")
			(net "M_B_CPU1_SB_DQ<5>")
		)
		(pad "110" smd rect
			(at -2.050034 34.425128 270)
			(size 0.519938 1.4986)
			(layers "F.Cu" "F.Mask" "F.Paste")
			(net "GND")
		)
		(pad "111" smd rect
			(at -2.050034 35.275012 270)
			(size 0.519938 1.4986)
			(layers "F.Cu" "F.Mask" "F.Paste")
			(net "M_B_CPU1_SB_DQ<8>")
		)
		(pad "112" smd rect
			(at -2.050034 36.124896 270)
			(size 0.519938 1.4986)
			(layers "F.Cu" "F.Mask" "F.Paste")
			(net "GND")
		)
		(pad "113" smd rect
			(at -2.050034 36.975034 270)
			(size 0.519938 1.4986)
			(layers "F.Cu" "F.Mask" "F.Paste")
			(net "M_B_CPU1_SB_DQ<9>")
		)
		(pad "114" smd rect
			(at -2.050034 37.824918 270)
			(size 0.519938 1.4986)
			(layers "F.Cu" "F.Mask" "F.Paste")
			(net "GND")
		)
		(pad "115" smd rect
			(at -2.050034 38.675056 270)
			(size 0.519938 1.4986)
			(layers "F.Cu" "F.Mask" "F.Paste")
			(net "M_B_CPU1_SB_DQS_DP<1>")
		)
		(pad "116" smd rect
			(at -2.050034 39.52494 270)
			(size 0.519938 1.4986)
			(layers "F.Cu" "F.Mask" "F.Paste")
			(net "M_B_CPU1_SB_DQS_DN<1>")
		)
		(pad "117" smd rect
			(at -2.050034 40.375078 270)
			(size 0.519938 1.4986)
			(layers "F.Cu" "F.Mask" "F.Paste")
			(net "GND")
		)
		(pad "118" smd rect
			(at -2.050034 41.224962 270)
			(size 0.519938 1.4986)
			(layers "F.Cu" "F.Mask" "F.Paste")
			(net "M_B_CPU1_SB_DQ<12>")
		)
		(pad "119" smd rect
			(at -2.050034 42.0751 270)
			(size 0.519938 1.4986)
			(layers "F.Cu" "F.Mask" "F.Paste")
			(net "GND")
		)
		(pad "120" smd rect
			(at -2.050034 42.924984 270)
			(size 0.519938 1.4986)
			(layers "F.Cu" "F.Mask" "F.Paste")
			(net "M_B_CPU1_SB_DQ<13>")
		)
		(pad "121" smd rect
			(at -2.050034 43.775122 270)
			(size 0.519938 1.4986)
			(layers "F.Cu" "F.Mask" "F.Paste")
			(net "GND")
		)
		(pad "122" smd rect
			(at -2.050034 44.625006 270)
			(size 0.519938 1.4986)
			(layers "F.Cu" "F.Mask" "F.Paste")
			(net "M_B_CPU1_SB_DQ<16>")
		)
		(pad "123" smd rect
			(at -2.050034 45.47489 270)
			(size 0.519938 1.4986)
			(layers "F.Cu" "F.Mask" "F.Paste")
			(net "GND")
		)
		(pad "124" smd rect
			(at -2.050034 46.325028 270)
			(size 0.519938 1.4986)
			(layers "F.Cu" "F.Mask" "F.Paste")
			(net "M_B_CPU1_SB_DQ<17>")
		)
		(pad "125" smd rect
			(at -2.050034 47.174912 270)
			(size 0.519938 1.4986)
			(layers "F.Cu" "F.Mask" "F.Paste")
			(net "GND")
		)
		(pad "126" smd rect
			(at -2.050034 48.02505 270)
			(size 0.519938 1.4986)
			(layers "F.Cu" "F.Mask" "F.Paste")
			(net "M_B_CPU1_SB_DQS_DP<2>")
		)
		(pad "127" smd rect
			(at -2.050034 48.874934 270)
			(size 0.519938 1.4986)
			(layers "F.Cu" "F.Mask" "F.Paste")
			(net "M_B_CPU1_SB_DQS_DN<2>")
		)
		(pad "128" smd rect
			(at -2.050034 49.725072 270)
			(size 0.519938 1.4986)
			(layers "F.Cu" "F.Mask" "F.Paste")
			(net "GND")
		)
		(pad "129" smd rect
			(at -2.050034 50.574956 270)
			(size 0.519938 1.4986)
			(layers "F.Cu" "F.Mask" "F.Paste")
			(net "M_B_CPU1_SB_DQ<20>")
		)
		(pad "130" smd rect
			(at -2.050034 51.425094 270)
			(size 0.519938 1.4986)
			(layers "F.Cu" "F.Mask" "F.Paste")
			(net "GND")
		)
		(pad "131" smd rect
			(at -2.050034 52.274978 270)
			(size 0.519938 1.4986)
			(layers "F.Cu" "F.Mask" "F.Paste")
			(net "M_B_CPU1_SB_DQ<21>")
		)
		(pad "132" smd rect
			(at -2.050034 53.125116 270)
			(size 0.519938 1.4986)
			(layers "F.Cu" "F.Mask" "F.Paste")
			(net "GND")
		)
		(pad "133" smd rect
			(at -2.050034 53.975 270)
			(size 0.519938 1.4986)
			(layers "F.Cu" "F.Mask" "F.Paste")
			(net "M_B_CPU1_SB_DQ<24>")
		)
		(pad "134" smd rect
			(at -2.050034 54.824884 270)
			(size 0.519938 1.4986)
			(layers "F.Cu" "F.Mask" "F.Paste")
			(net "GND")
		)
		(pad "135" smd rect
			(at -2.050034 55.675022 270)
			(size 0.519938 1.4986)
			(layers "F.Cu" "F.Mask" "F.Paste")
			(net "M_B_CPU1_SB_DQ<25>")
		)
		(pad "136" smd rect
			(at -2.050034 56.524906 270)
			(size 0.519938 1.4986)
			(layers "F.Cu" "F.Mask" "F.Paste")
			(net "GND")
		)
		(pad "137" smd rect
			(at -2.050034 57.375044 270)
			(size 0.519938 1.4986)
			(layers "F.Cu" "F.Mask" "F.Paste")
			(net "M_B_CPU1_SB_DQS_DP<3>")
		)
	)
)
